G04 ================== begin FILE IDENTIFICATION RECORD ==================*
G04 Layout Name:  9051_F0T_Panel_BD_Front_D_v02_20221209_1310.brd*
G04 Film Name:    gnd1*
G04 File Format:  Gerber RS274X*
G04 File Origin:  Cadence Allegro 17.2-S081*
G04 Origin Date:  Mon Dec 12 15:51:17 2022*
G04 *
G04 Layer:  DRAWING FORMAT/TITLE_BLOCK_A*
G04 Layer:  PIN/SPECIAL_DRILL*
G04 Layer:  DRAWING FORMAT/TITLE_BLOCK*
G04 Layer:  VIA CLASS/GND1*
G04 Layer:  PIN/GND1*
G04 Layer:  MANUFACTURING/PHOTOPLOT_OUTLINE*
G04 Layer:  ETCH/GND1*
G04 Layer:  DRAWING FORMAT/TITLE_DATA_GND1*
G04 *
G04 Offset:    (0.00 0.00)*
G04 Mirror:    No*
G04 Mode:      Negative*
G04 Rotation:  0*
G04 FullContactRelief:  No*
G04 UndefLineWidth:     6.00*
G04 ================== end FILE IDENTIFICATION RECORD ====================*
%FSLAX25Y25*MOIN*%
%IR0*IPPOS*OFA0.00000B0.00000*MIA0B0*SFA1.00000B1.00000*%
%ADD13C,.03*%
%ADD12C,.052*%
%ADD33C,.071*%
%ADD24C,.082*%
%AMMACRO21*
4,1,36,.0025,0.0,
.002462,.000434,
.002349,.000855,
.002165,.00125,
.001915,.001607,
.001607,.001915,
.00125,.002165,
.000855,.002349,
.000434,.002462,
0.0,.0025,
-.000434,.002462,
-.000855,.002349,
-.00125,.002165,
-.001607,.001915,
-.001915,.001607,
-.002165,.00125,
-.002349,.000855,
-.002462,.000434,
-.0025,0.0,
-.002462,-.000434,
-.002349,-.000855,
-.002165,-.00125,
-.001915,-.001607,
-.001607,-.001915,
-.00125,-.002165,
-.000855,-.002349,
-.000434,-.002462,
0.0,-.0025,
.000434,-.002462,
.000855,-.002349,
.00125,-.002165,
.001607,-.001915,
.001915,-.001607,
.002165,-.00125,
.002349,-.000855,
.002462,-.000434,
.0025,0.0,
225.*
%
%ADD21MACRO21*%
%AMMACRO20*
4,1,36,.0025,0.0,
.002462,.000434,
.002349,.000855,
.002165,.00125,
.001915,.001607,
.001607,.001915,
.00125,.002165,
.000855,.002349,
.000434,.002462,
0.0,.0025,
-.000434,.002462,
-.000855,.002349,
-.00125,.002165,
-.001607,.001915,
-.001915,.001607,
-.002165,.00125,
-.002349,.000855,
-.002462,.000434,
-.0025,0.0,
-.002462,-.000434,
-.002349,-.000855,
-.002165,-.00125,
-.001915,-.001607,
-.001607,-.001915,
-.00125,-.002165,
-.000855,-.002349,
-.000434,-.002462,
0.0,-.0025,
.000434,-.002462,
.000855,-.002349,
.00125,-.002165,
.001607,-.001915,
.001915,-.001607,
.002165,-.00125,
.002349,-.000855,
.002462,-.000434,
.0025,0.0,
270.*
%
%ADD20MACRO20*%
%AMMACRO19*
4,1,36,.0025,0.0,
.002462,.000434,
.002349,.000855,
.002165,.00125,
.001915,.001607,
.001607,.001915,
.00125,.002165,
.000855,.002349,
.000434,.002462,
0.0,.0025,
-.000434,.002462,
-.000855,.002349,
-.00125,.002165,
-.001607,.001915,
-.001915,.001607,
-.002165,.00125,
-.002349,.000855,
-.002462,.000434,
-.0025,0.0,
-.002462,-.000434,
-.002349,-.000855,
-.002165,-.00125,
-.001915,-.001607,
-.001607,-.001915,
-.00125,-.002165,
-.000855,-.002349,
-.000434,-.002462,
0.0,-.0025,
.000434,-.002462,
.000855,-.002349,
.00125,-.002165,
.001607,-.001915,
.001915,-.001607,
.002165,-.00125,
.002349,-.000855,
.002462,-.000434,
.0025,0.0,
315.*
%
%ADD19MACRO19*%
%AMMACRO16*
4,1,36,.0025,0.0,
.002462,.000434,
.002349,.000855,
.002165,.00125,
.001915,.001607,
.001607,.001915,
.00125,.002165,
.000855,.002349,
.000434,.002462,
0.0,.0025,
-.000434,.002462,
-.000855,.002349,
-.00125,.002165,
-.001607,.001915,
-.001915,.001607,
-.002165,.00125,
-.002349,.000855,
-.002462,.000434,
-.0025,0.0,
-.002462,-.000434,
-.002349,-.000855,
-.002165,-.00125,
-.001915,-.001607,
-.001607,-.001915,
-.00125,-.002165,
-.000855,-.002349,
-.000434,-.002462,
0.0,-.0025,
.000434,-.002462,
.000855,-.002349,
.00125,-.002165,
.001607,-.001915,
.001915,-.001607,
.002165,-.00125,
.002349,-.000855,
.002462,-.000434,
.0025,0.0,
180.*
%
%ADD16MACRO16*%
%AMMACRO38*
4,1,36,.003,0.0,
.002954,.000521,
.002819,.001026,
.002598,.0015,
.002298,.001928,
.001928,.002298,
.0015,.002598,
.001026,.002819,
.000521,.002954,
0.0,.003,
-.000521,.002954,
-.001026,.002819,
-.0015,.002598,
-.001928,.002298,
-.002298,.001928,
-.002598,.0015,
-.002819,.001026,
-.002954,.000521,
-.003,0.0,
-.002954,-.000521,
-.002819,-.001026,
-.002598,-.0015,
-.002298,-.001928,
-.001928,-.002298,
-.0015,-.002598,
-.001026,-.002819,
-.000521,-.002954,
0.0,-.003,
.000521,-.002954,
.001026,-.002819,
.0015,-.002598,
.001928,-.002298,
.002298,-.001928,
.002598,-.0015,
.002819,-.001026,
.002954,-.000521,
.003,0.0,
270.*
%
%ADD38MACRO38*%
%AMMACRO35*
4,1,36,-.0025,0.0,
-.002462,.000434,
-.002349,.000855,
-.002165,.00125,
-.001915,.001607,
-.001607,.001915,
-.00125,.002165,
-.000855,.002349,
-.000434,.002462,
0.0,.0025,
.000434,.002462,
.000855,.002349,
.00125,.002165,
.001607,.001915,
.001915,.001607,
.002165,.00125,
.002349,.000855,
.002462,.000434,
.0025,0.0,
.002462,-.000434,
.002349,-.000855,
.002165,-.00125,
.001915,-.001607,
.001607,-.001915,
.00125,-.002165,
.000855,-.002349,
.000434,-.002462,
0.0,-.0025,
-.000434,-.002462,
-.000855,-.002349,
-.00125,-.002165,
-.001607,-.001915,
-.001915,-.001607,
-.002165,-.00125,
-.002349,-.000855,
-.002462,-.000434,
-.0025,0.0,
270.*
%
%ADD35MACRO35*%
%ADD37C,.0435*%
%ADD27C,.048*%
%ADD22C,.058*%
%ADD30C,.087*%
%AMMACRO25*
4,1,13,.01917,.00857,
.020367,.005111,
.020945,.001497,
.020887,-.002163,
.020194,-.005757,
.01917,-.00857,
.02438,-.01377,
.026401,-.009327,
.027619,-.004601,
.027999,.000265,
.027527,.005123,
.02622,.009825,
.02438,.01377,
.01917,.00857,
0.0*
4,1,13,.00857,-.01917,
.005111,-.020367,
.001497,-.020945,
-.002163,-.020887,
-.005757,-.020194,
-.00857,-.01917,
-.01377,-.02438,
-.009327,-.026401,
-.004601,-.027619,
.000265,-.027999,
.005123,-.027527,
.009825,-.02622,
.01377,-.02438,
.00857,-.01917,
0.0*
4,1,13,-.01917,-.00857,
-.020367,-.005111,
-.020945,-.001497,
-.020887,.002163,
-.020194,.005757,
-.01917,.00857,
-.02438,.01377,
-.026401,.009327,
-.027619,.004601,
-.027999,-.000265,
-.027527,-.005123,
-.02622,-.009825,
-.02438,-.01377,
-.01917,-.00857,
0.0*
4,1,13,-.00857,.01917,
-.005111,.020367,
-.001497,.020945,
.002163,.020887,
.005757,.020194,
.00857,.01917,
.01377,.02438,
.009327,.026401,
.004601,.027619,
-.000265,.027999,
-.005123,.027527,
-.009825,.02622,
-.01377,.02438,
-.00857,.01917,
0.0*
%
%ADD25MACRO25*%
%AMMACRO28*
4,1,15,.01993,.00932,
.021246,.005718,
.021916,.001941,
.02192,-.001894,
.021258,-.005671,
.01995,-.009276,
.01993,-.00932,
.02511,-.01451,
.027248,-.009929,
.028558,-.005047,
.029001,-.000011,
.028562,.005025,
.027256,.009909,
.025121,.014491,
.02511,.01451,
.01993,.00932,
0.0*
4,1,15,.00932,-.01993,
.005718,-.021246,
.001941,-.021916,
-.001894,-.02192,
-.005671,-.021258,
-.009276,-.01995,
-.00932,-.01993,
-.01451,-.02511,
-.009929,-.027248,
-.005047,-.028558,
-.000011,-.029001,
.005025,-.028562,
.009909,-.027256,
.014491,-.025121,
.01451,-.02511,
.00932,-.01993,
0.0*
4,1,15,-.01993,-.00932,
-.021246,-.005718,
-.021916,-.001941,
-.02192,.001894,
-.021258,.005671,
-.01995,.009276,
-.01993,.00932,
-.02511,.01451,
-.027248,.009929,
-.028558,.005047,
-.029001,.000011,
-.028562,-.005025,
-.027256,-.009909,
-.025121,-.014491,
-.02511,-.01451,
-.01993,-.00932,
0.0*
4,1,15,-.00932,.01993,
-.005718,.021246,
-.001941,.021916,
.001894,.02192,
.005671,.021258,
.009276,.01995,
.00932,.01993,
.01451,.02511,
.009929,.027248,
.005047,.028558,
.000011,.029001,
-.005025,.028562,
-.009909,.027256,
-.014491,.025121,
-.01451,.02511,
-.00932,.01993,
0.0*
%
%ADD28MACRO28*%
%AMMACRO26*
4,1,20,-.0075,-.05558,
-.012609,-.05382,
-.017336,-.0512,
-.021535,-.047799,
-.02508,-.043721,
-.027863,-.039089,
-.029799,-.034044,
-.03083,-.028739,
-.031,-.0255,
-.031,-.0075,
-.024,-.0075,
-.024,-.0255,
-.023635,-.029668,
-.022552,-.033709,
-.020784,-.037501,
-.018384,-.040929,
-.015426,-.043887,
-.011999,-.046287,
-.008207,-.048055,
-.0075,-.0483,
-.0075,-.05558,
0.0*
4,1,20,.0075,-.05558,
.0075,-.0483,
.011345,-.046651,
.014846,-.044359,
.017895,-.041494,
.0204,-.038143,
.022286,-.034408,
.023494,-.030402,
.023988,-.026248,
.024,-.0255,
.024,-.0075,
.031,-.0075,
.031,-.0255,
.030529,-.030883,
.02913,-.036103,
.026847,-.041001,
.023747,-.045427,
.019926,-.049248,
.015499,-.052348,
.010602,-.054632,
.0075,-.05558,
0.0*
4,1,20,-.031,.0075,
-.031,.0255,
-.030529,.030883,
-.02913,.036103,
-.026847,.041001,
-.023747,.045427,
-.019926,.049248,
-.015499,.052348,
-.010602,.054632,
-.0075,.05558,
-.0075,.0483,
-.011345,.046651,
-.014846,.044359,
-.017895,.041494,
-.0204,.038143,
-.022286,.034408,
-.023494,.030402,
-.023988,.026248,
-.024,.0255,
-.024,.0075,
-.031,.0075,
0.0*
4,1,20,.024,.0075,
.024,.0255,
.023635,.029668,
.022552,.033709,
.020784,.037501,
.018384,.040929,
.015426,.043887,
.011999,.046287,
.008207,.048055,
.0075,.0483,
.0075,.05558,
.012609,.05382,
.017336,.0512,
.021535,.047799,
.02508,.043721,
.027863,.039089,
.029799,.034044,
.03083,.028739,
.031,.0255,
.031,.0075,
.024,.0075,
0.0*
%
%ADD26MACRO26*%
%AMMACRO23*
4,1,15,.02364,.01304,
.025545,.008737,
.026674,.004168,
.026993,-.000527,
.026491,-.005206,
.025185,-.009727,
.02364,-.01304,
.02875,-.01815,
.031465,-.012882,
.033224,-.007222,
.033973,-.001343,
.03369,.004576,
.032384,.010357,
.030093,.015823,
.02875,.01815,
.02364,.01304,
0.0*
4,1,15,.01304,-.02364,
.008737,-.025545,
.004168,-.026674,
-.000527,-.026993,
-.005206,-.026491,
-.009727,-.025185,
-.01304,-.02364,
-.01815,-.02875,
-.012882,-.031465,
-.007222,-.033224,
-.001343,-.033973,
.004576,-.03369,
.010357,-.032384,
.015823,-.030093,
.01815,-.02875,
.01304,-.02364,
0.0*
4,1,15,-.02364,-.01304,
-.025545,-.008737,
-.026674,-.004168,
-.026993,.000527,
-.026491,.005206,
-.025185,.009727,
-.02364,.01304,
-.02875,.01815,
-.031465,.012882,
-.033224,.007222,
-.033973,.001343,
-.03369,-.004576,
-.032384,-.010357,
-.030093,-.015823,
-.02875,-.01815,
-.02364,-.01304,
0.0*
4,1,15,-.01304,.02364,
-.008737,.025545,
-.004168,.026674,
.000527,.026993,
.005206,.026491,
.009727,.025185,
.01304,.02364,
.01815,.02875,
.012882,.031465,
.007222,.033224,
.001343,.033973,
-.004576,.03369,
-.010357,.032384,
-.015823,.030093,
-.01815,.02875,
-.01304,.02364,
0.0*
%
%ADD23MACRO23*%
%AMMACRO31*
4,1,15,.03682,.01914,
.039584,.012455,
.041146,.005393,
.041457,-.001834,
.040509,-.009005,
.03833,-.015903,
.03682,-.01914,
.04197,-.0243,
.045552,-.016643,
.04775,-.00848,
.048497,-.000059,
.047771,.008363,
.045593,.016531,
.042029,.024197,
.04197,.0243,
.03682,.01914,
0.0*
4,1,15,.01914,-.03682,
.012455,-.039584,
.005393,-.041146,
-.001834,-.041457,
-.009005,-.040509,
-.015903,-.03833,
-.01914,-.03682,
-.0243,-.04197,
-.016643,-.045552,
-.00848,-.04775,
-.000059,-.048497,
.008363,-.047771,
.016531,-.045593,
.024197,-.042029,
.0243,-.04197,
.01914,-.03682,
0.0*
4,1,15,-.03682,-.01914,
-.039584,-.012455,
-.041146,-.005393,
-.041457,.001834,
-.040509,.009005,
-.03833,.015903,
-.03682,.01914,
-.04197,.0243,
-.045552,.016643,
-.04775,.00848,
-.048497,.000059,
-.047771,-.008363,
-.045593,-.016531,
-.042029,-.024197,
-.04197,-.0243,
-.03682,-.01914,
0.0*
4,1,15,-.01914,.03682,
-.012455,.039584,
-.005393,.041146,
.001834,.041457,
.009005,.040509,
.015903,.03833,
.01914,.03682,
.0243,.04197,
.016643,.045552,
.00848,.04775,
.000059,.048497,
-.008363,.047771,
-.016531,.045593,
-.024197,.042029,
-.0243,.04197,
-.01914,.03682,
0.0*
%
%ADD31MACRO31*%
%AMMACRO14*
4,1,36,0.0,.01,
-.001736,.009848,
-.00342,.009397,
-.005,.00866,
-.006428,.00766,
-.00766,.006428,
-.00866,.005,
-.009397,.00342,
-.009848,.001736,
-.01,0.0,
-.009848,-.001736,
-.009397,-.00342,
-.00866,-.005,
-.00766,-.006428,
-.006428,-.00766,
-.005,-.00866,
-.00342,-.009397,
-.001736,-.009848,
0.0,-.01,
.001736,-.009848,
.00342,-.009397,
.005,-.00866,
.006428,-.00766,
.00766,-.006428,
.00866,-.005,
.009397,-.00342,
.009848,-.001736,
.01,0.0,
.009848,.001736,
.009397,.00342,
.00866,.005,
.00766,.006428,
.006428,.00766,
.005,.00866,
.00342,.009397,
.001736,.009848,
0.0,.01,
180.*
%
%ADD14MACRO14*%
%ADD10C,.125*%
%ADD15C,.155*%
%ADD18C,.149*%
%AMMACRO34*
4,1,36,.0025,0.0,
.002462,.000434,
.002349,.000855,
.002165,.00125,
.001915,.001607,
.001607,.001915,
.00125,.002165,
.000855,.002349,
.000434,.002462,
0.0,.0025,
-.000434,.002462,
-.000855,.002349,
-.00125,.002165,
-.001607,.001915,
-.001915,.001607,
-.002165,.00125,
-.002349,.000855,
-.002462,.000434,
-.0025,0.0,
-.002462,-.000434,
-.002349,-.000855,
-.002165,-.00125,
-.001915,-.001607,
-.001607,-.001915,
-.00125,-.002165,
-.000855,-.002349,
-.000434,-.002462,
0.0,-.0025,
.000434,-.002462,
.000855,-.002349,
.00125,-.002165,
.001607,-.001915,
.001915,-.001607,
.002165,-.00125,
.002349,-.000855,
.002462,-.000434,
.0025,0.0,
90.*
%
%ADD34MACRO34*%
%AMMACRO39*
4,1,36,.003,0.0,
.002954,.000521,
.002819,.001026,
.002598,.0015,
.002298,.001928,
.001928,.002298,
.0015,.002598,
.001026,.002819,
.000521,.002954,
0.0,.003,
-.000521,.002954,
-.001026,.002819,
-.0015,.002598,
-.001928,.002298,
-.002298,.001928,
-.002598,.0015,
-.002819,.001026,
-.002954,.000521,
-.003,0.0,
-.002954,-.000521,
-.002819,-.001026,
-.002598,-.0015,
-.002298,-.001928,
-.001928,-.002298,
-.0015,-.002598,
-.001026,-.002819,
-.000521,-.002954,
0.0,-.003,
.000521,-.002954,
.001026,-.002819,
.0015,-.002598,
.001928,-.002298,
.002298,-.001928,
.002598,-.0015,
.002819,-.001026,
.002954,-.000521,
.003,0.0,
90.*
%
%ADD39MACRO39*%
%AMMACRO36*
4,1,36,-.0025,0.0,
-.002462,.000434,
-.002349,.000855,
-.002165,.00125,
-.001915,.001607,
-.001607,.001915,
-.00125,.002165,
-.000855,.002349,
-.000434,.002462,
0.0,.0025,
.000434,.002462,
.000855,.002349,
.00125,.002165,
.001607,.001915,
.001915,.001607,
.002165,.00125,
.002349,.000855,
.002462,.000434,
.0025,0.0,
.002462,-.000434,
.002349,-.000855,
.002165,-.00125,
.001915,-.001607,
.001607,-.001915,
.00125,-.002165,
.000855,-.002349,
.000434,-.002462,
0.0,-.0025,
-.000434,-.002462,
-.000855,-.002349,
-.00125,-.002165,
-.001607,-.001915,
-.001915,-.001607,
-.002165,-.00125,
-.002349,-.000855,
-.002462,-.000434,
-.0025,0.0,
90.*
%
%ADD36MACRO36*%
%AMMACRO11*
4,1,36,.0025,0.0,
.002462,.000434,
.002349,.000855,
.002165,.00125,
.001915,.001607,
.001607,.001915,
.00125,.002165,
.000855,.002349,
.000434,.002462,
0.0,.0025,
-.000434,.002462,
-.000855,.002349,
-.00125,.002165,
-.001607,.001915,
-.001915,.001607,
-.002165,.00125,
-.002349,.000855,
-.002462,.000434,
-.0025,0.0,
-.002462,-.000434,
-.002349,-.000855,
-.002165,-.00125,
-.001915,-.001607,
-.001607,-.001915,
-.00125,-.002165,
-.000855,-.002349,
-.000434,-.002462,
0.0,-.0025,
.000434,-.002462,
.000855,-.002349,
.00125,-.002165,
.001607,-.001915,
.001915,-.001607,
.002165,-.00125,
.002349,-.000855,
.002462,-.000434,
.0025,0.0,
0.0*
%
%ADD11MACRO11*%
%ADD17C,.188*%
%AMMACRO32*
4,1,15,.03682,.01914,
.039584,.012455,
.041146,.005393,
.041457,-.001834,
.040509,-.009005,
.03833,-.015903,
.03682,-.01914,
.04197,-.0243,
.045552,-.016643,
.04775,-.00848,
.048497,-.000059,
.047771,.008363,
.045593,.016531,
.042029,.024197,
.04197,.0243,
.03682,.01914,
180.*
4,1,15,.01914,-.03682,
.012455,-.039584,
.005393,-.041146,
-.001834,-.041457,
-.009005,-.040509,
-.015903,-.03833,
-.01914,-.03682,
-.0243,-.04197,
-.016643,-.045552,
-.00848,-.04775,
-.000059,-.048497,
.008363,-.047771,
.016531,-.045593,
.024197,-.042029,
.0243,-.04197,
.01914,-.03682,
180.*
4,1,15,-.03682,-.01914,
-.039584,-.012455,
-.041146,-.005393,
-.041457,.001834,
-.040509,.009005,
-.03833,.015903,
-.03682,.01914,
-.04197,.0243,
-.045552,.016643,
-.04775,.00848,
-.048497,.000059,
-.047771,-.008363,
-.045593,-.016531,
-.042029,-.024197,
-.04197,-.0243,
-.03682,-.01914,
180.*
4,1,15,-.01914,.03682,
-.012455,.039584,
-.005393,.041146,
.001834,.041457,
.009005,.040509,
.015903,.03833,
.01914,.03682,
.0243,.04197,
.016643,.045552,
.00848,.04775,
.000059,.048497,
-.008363,.047771,
-.016531,.045593,
-.024197,.042029,
-.0243,.04197,
-.01914,.03682,
180.*
%
%ADD32MACRO32*%
%AMMACRO29*
4,1,20,-.0075,-.0348,
-.0075,-.04208,
-.012609,-.04032,
-.017336,-.0377,
-.021535,-.034299,
-.02508,-.030221,
-.027863,-.025589,
-.029799,-.020544,
-.03083,-.015239,
-.031,-.012,
-.031,-.0075,
-.024,-.0075,
-.024,-.012,
-.023635,-.016168,
-.022552,-.020209,
-.020784,-.024001,
-.018384,-.027429,
-.015426,-.030387,
-.011999,-.032787,
-.008207,-.034555,
-.0075,-.0348,
0.0*
4,1,20,.0075,-.04208,
.0075,-.0348,
.011345,-.033151,
.014846,-.030859,
.017895,-.027994,
.0204,-.024643,
.022286,-.020908,
.023494,-.016902,
.023988,-.012748,
.024,-.012,
.024,-.0075,
.031,-.0075,
.031,-.012,
.030529,-.017383,
.02913,-.022603,
.026847,-.027501,
.023747,-.031927,
.019926,-.035748,
.015499,-.038848,
.010602,-.041132,
.0075,-.04208,
0.0*
4,1,20,-.0075,.04208,
-.0075,.0348,
-.011345,.033151,
-.014846,.030859,
-.017895,.027994,
-.0204,.024643,
-.022286,.020908,
-.023494,.016902,
-.023988,.012748,
-.024,.012,
-.024,.0075,
-.031,.0075,
-.031,.012,
-.030529,.017383,
-.02913,.022603,
-.026847,.027501,
-.023747,.031927,
-.019926,.035748,
-.015499,.038848,
-.010602,.041132,
-.0075,.04208,
0.0*
4,1,20,.0075,.0348,
.0075,.04208,
.012609,.04032,
.017336,.0377,
.021535,.034299,
.02508,.030221,
.027863,.025589,
.029799,.020544,
.03083,.015239,
.031,.012,
.031,.0075,
.024,.0075,
.024,.012,
.023635,.016168,
.022552,.020209,
.020784,.024001,
.018384,.027429,
.015426,.030387,
.011999,.032787,
.008207,.034555,
.0075,.0348,
0.0*
%
%ADD29MACRO29*%
%ADD40C,.006*%
%ADD45C,.07306*%
%ADD42C,.08607*%
%ADD43C,.08609*%
%ADD44C,.16506*%
%ADD41C,.19806*%
G75*
%LPD*%
G75*
G36*
G01X-247901Y-428634D02*
X2091018D01*
Y1008173D01*
X-247901D01*
Y-428634D01*
G37*
%LPC*%
G75*
G36*
G01X113583Y337169D02*
G02X119453Y331299I0J-5870D01*
G01Y322835D01*
G03X129331Y312957I9878J0D01*
G01X142520D01*
G02X148390Y307087I0J-5870D01*
G01Y283263D01*
G03X151106Y276461I9878J1D01*
G02X152720Y272419I-4257J-4043D01*
G01Y190480D01*
X152729Y190471D01*
Y190160D01*
X152720Y190151D01*
Y7869D01*
G02X152598Y6682I-5870J4D01*
G01Y6680D01*
G02X146855Y2043I-5743J1238D01*
G01X7879D01*
G02X2005Y7917I0J5874D01*
G01Y272460D01*
G02X2006Y272576I5875J7D01*
G01Y272578D01*
G02X3618Y276461I5869J-160D01*
G03X6333Y283055I-7161J6804D01*
G03X6336Y283307I-9871J244D01*
G01Y307130D01*
G02X6337Y307244I5874J5D01*
G01Y307246D01*
G02X12205Y312957I5868J-159D01*
G01X42716D01*
G03X52592Y322627I0J9878D01*
G03X52595Y322878I-9871J243D01*
G01Y331342D01*
G02X52596Y331456I5874J5D01*
G01Y331458D01*
G02X58464Y337169I5868J-159D01*
G01X113583D01*
G37*
G36*
G01X333217Y2006D02*
G02X333153I-32J6017D01*
G01X333151D01*
G02X327200Y7957I1J5952D01*
G01Y7959D01*
G02Y8023I6017J32D01*
G01Y188030D01*
X327196Y188034D01*
Y192516D01*
X327200Y192520D01*
Y272669D01*
G02X327400Y272869I200J0D01*
G01X389921D01*
G02X390121Y272669I0J-200D01*
G01Y7907D01*
G02X384220Y2006I-5901J0D01*
G01X333217D01*
G37*
G36*
G01X327283Y679348D02*
Y679352D01*
G02X333166Y684220I5883J-1121D01*
G01X384220D01*
G02X390121Y678319I0J-5901D01*
G01Y275069D01*
G02X389921Y274869I-200J0D01*
G01X327400D01*
G02X327200Y275069I0J200D01*
G01Y678579D01*
Y678587D01*
G02X327283Y679348I5868J-255D01*
G37*
%LPD*%
G75*
G36*
G01X91881Y72165D02*
G02X97883I3001J0D01*
G02X97321Y70417I-3001J0D01*
G03X97284Y70301I163J-116D01*
G01Y66153D01*
G03X97321Y66037I200J0D01*
G02X97882Y64291I-2438J-1746D01*
G02X91882I-3000J0D01*
G02X92443Y66037I2999J0D01*
G03X92480Y66153I-163J116D01*
G01Y70301D01*
G03X92443Y70417I-200J0D01*
G02X91881Y72165I2439J1748D01*
G37*
G36*
G01X18076Y279449D02*
Y282093D01*
G03X16771Y285783I-5872J-1D01*
G02X35197I9213J7445D01*
G03X33892Y282094I4566J-3691D01*
G01Y279449D01*
G02X18076I-7908J0D01*
G37*
G36*
G01X144130Y43425D02*
G02X128312I-7909J0D01*
G01Y46070D01*
G03X127008Y49759I-5872J-1D01*
G02X145434I9213J7445D01*
G03X144130Y46070I4567J-3689D01*
G01Y43425D01*
G37*
G54D45*
X380000Y597350D03*
X370000D03*
Y622350D03*
X380000D03*
X350500Y597350D03*
X340500D03*
Y622350D03*
X350500D03*
X370000Y341336D03*
X380000D03*
Y316336D03*
X370000D03*
X340500Y445150D03*
X350500D03*
Y420150D03*
X340500D03*
G54D42*
X64174Y294685D03*
G54D43*
X107874D03*
G54D44*
X14000Y255500D03*
X60989Y131906D03*
X134016Y147928D03*
X372440Y19685D03*
Y666535D03*
G54D41*
X24016Y58661D03*
X129134Y247543D03*
G54D13*
X10315Y13000D03*
X8000Y103500D03*
Y114500D03*
X11500Y196000D03*
Y188000D03*
Y204000D03*
X19500Y209500D03*
Y217500D03*
Y225500D03*
Y233500D03*
Y241500D03*
X59500Y55000D03*
X52000Y81000D03*
X59500Y95000D03*
X42400Y86500D03*
X41500Y103500D03*
X41038Y112537D03*
X55925Y204000D03*
X63600Y34192D03*
X72555Y46921D03*
X64500Y63500D03*
X66925Y70000D03*
X70075Y64500D03*
X68720Y54000D03*
X81729Y77772D03*
X73000Y91000D03*
Y87000D03*
X65000Y73500D03*
X73000Y95000D03*
X78500Y110000D03*
Y112500D03*
X75425Y102000D03*
X59500Y117960D03*
X76000Y123000D03*
Y126500D03*
X78340Y136000D03*
X67000Y177500D03*
X66500Y181500D03*
Y185500D03*
Y189500D03*
Y193500D03*
X68500Y231500D03*
X76500Y239500D03*
Y235500D03*
Y231500D03*
X64000Y258000D03*
X66500D03*
X65925Y247000D03*
X72500Y258000D03*
X70000D03*
X75394Y288205D03*
X68308D03*
X84500Y76500D03*
X81000Y91000D03*
Y95000D03*
X83500Y133000D03*
Y129500D03*
X88500Y123500D03*
X92500Y126000D03*
X80310Y138735D03*
X96654Y288205D03*
X89567D03*
X106954Y21716D03*
X111965Y11716D03*
X109812Y16716D03*
X122130Y30217D03*
X107318Y63176D03*
X106970Y65827D03*
Y68327D03*
X112000Y147000D03*
Y150500D03*
X115000Y147000D03*
Y150500D03*
X132000Y10500D03*
X139500D03*
X127500Y6716D03*
X137000Y84500D03*
Y88000D03*
Y92000D03*
X134500Y136500D03*
Y133000D03*
Y129500D03*
Y126000D03*
Y122500D03*
Y119000D03*
X148500Y76000D03*
Y84000D03*
Y92000D03*
Y108000D03*
Y100000D03*
G54D12*
X10315Y20079D03*
X33937D03*
X20315D03*
X43937D03*
G54D33*
X350500Y420150D03*
X340500D03*
X350500Y445150D03*
X340500D03*
Y597350D03*
X350500D03*
X340500Y622350D03*
X350500D03*
X380000Y316336D03*
X370000D03*
X380000Y341336D03*
X370000D03*
Y597350D03*
X380000D03*
X370000Y622350D03*
X380000D03*
G54D16*
X13984Y279449D03*
X78937Y270653D03*
X80119Y288205D03*
X86024Y270653D03*
X93111D03*
X84843Y288205D03*
X101378D03*
X106103D03*
X124221Y43425D03*
G54D19*
X34469Y270964D03*
X144706Y34940D03*
G54D20*
X25984Y267449D03*
X136221Y31425D03*
X350539Y607802D03*
X351845Y614080D03*
X349330Y614095D03*
X340010Y607802D03*
X369510D03*
X378830Y614095D03*
X381345Y614080D03*
X380039Y607802D03*
G54D21*
X17499Y270964D03*
X127736Y34940D03*
G54D24*
X64174Y294685D03*
X107874D03*
G54D35*
X341684Y431703D03*
X339169Y431688D03*
X349698D03*
X352213Y431703D03*
X344419Y428405D03*
X346934Y428420D03*
X352199Y428435D03*
X349684Y428420D03*
X371184Y327889D03*
X368669Y327874D03*
X379198D03*
X373919Y324591D03*
X376434Y324606D03*
X379184D03*
X381713Y327889D03*
X381699Y324621D03*
G54D38*
X370195Y83000D03*
X380195D03*
G54D27*
X101969Y52480D03*
Y68228D03*
Y60354D03*
X94882Y64291D03*
Y72165D03*
Y82008D03*
X101969Y83976D03*
Y76102D03*
G54D37*
X370195Y93000D03*
X380195D03*
Y247618D03*
X370195D03*
G54D22*
X57480Y26299D03*
X77480D03*
G54D30*
X339937Y104912D03*
X349937D03*
X352033Y234525D03*
X342033D03*
G54D25*
X61516Y326772D03*
Y314961D03*
X110532Y326772D03*
Y314961D03*
G54D28*
X94882Y54449D03*
G54D26*
X87756Y47244D03*
X109095Y89370D03*
G54D23*
X67480Y26299D03*
G54D31*
X344937Y91728D03*
G54D14*
X13553Y48198D03*
Y69124D03*
X9218Y58661D03*
X34479Y48198D03*
X24016Y43863D03*
X34479Y69124D03*
X24016Y73459D03*
X38814Y58661D03*
X118671Y237080D03*
Y258006D03*
X114336Y247543D03*
X139597Y237080D03*
X129134Y232745D03*
Y262341D03*
X139597Y258006D03*
X143932Y247543D03*
G54D10*
X-58189Y19685D03*
Y666535D03*
X372440Y19685D03*
Y666535D03*
G54D15*
X14000Y255500D03*
X60989Y131906D03*
X134016Y147928D03*
G54D18*
X25984Y279449D03*
X136221Y43425D03*
G54D34*
X350990Y434698D03*
X341670Y428405D03*
X339155Y428420D03*
X340461Y434698D03*
X371170Y324591D03*
X368655Y324606D03*
X369961Y330884D03*
X380490D03*
G54D11*
X5192Y3841D03*
X3004Y90860D03*
Y106468D03*
X8000Y99500D03*
Y110500D03*
X16000Y98441D03*
Y109441D03*
X3004Y126468D03*
Y146468D03*
Y166468D03*
X11500Y200000D03*
Y192000D03*
Y184000D03*
X3004Y186468D03*
Y206468D03*
Y226468D03*
Y246468D03*
X7348Y302588D03*
X7337Y292952D03*
X27028Y3019D03*
X33000Y186000D03*
X19500Y221500D03*
Y213500D03*
Y229500D03*
Y237500D03*
Y245500D03*
X35701Y311937D03*
X16801Y311946D03*
X46184Y3014D03*
X59586Y40000D03*
X48941Y89500D03*
X54059Y102500D03*
X41000Y213532D03*
X59075Y204000D03*
X56500Y261000D03*
X57800Y263900D03*
X37984Y279449D03*
X51404Y316245D03*
X53595Y331234D03*
X60867Y3014D03*
X81000Y8000D03*
X77382Y58000D03*
X62500Y55000D03*
X77453Y77500D03*
X66000Y118000D03*
X70000Y138500D03*
X70500Y177500D03*
X64075Y200000D03*
X76500Y227500D03*
X76400Y258000D03*
X69075Y247000D03*
X75700Y263900D03*
X64764Y288205D03*
X71851D03*
X68968Y336145D03*
X80697Y3016D03*
X98502D03*
X99500Y9000D03*
X91000Y18500D03*
X99000Y65500D03*
X84500Y95000D03*
X81500Y126500D03*
X94500Y129000D03*
X93111Y288205D03*
X100197Y270653D03*
X83076Y336146D03*
X118500Y6716D03*
X117186Y3014D03*
X113181Y31701D03*
X118000Y116500D03*
X120500Y136500D03*
Y129500D03*
Y133000D03*
Y126000D03*
X107284Y270653D03*
X118455Y323862D03*
X116870Y334863D03*
X103076Y336146D03*
X136936Y3035D03*
X128385Y80000D03*
X133500Y160000D03*
X132500Y185000D03*
X129715Y311960D03*
X150330Y4601D03*
X151688Y13776D03*
X148221Y43425D03*
X151706Y72716D03*
X151683Y90942D03*
X148500Y88000D03*
Y80000D03*
X151684Y112798D03*
X148500Y96000D03*
Y112000D03*
Y104000D03*
X151684Y132682D03*
X148500Y136500D03*
Y133000D03*
Y129500D03*
Y126000D03*
Y122500D03*
Y119000D03*
Y115500D03*
X151683Y151482D03*
X151705Y172913D03*
X151663Y192669D03*
X151662Y212615D03*
X151704Y232645D03*
X151705Y252655D03*
X144561Y311483D03*
G54D36*
X338801Y614065D03*
X341316Y614080D03*
X338787Y610797D03*
X341302Y610812D03*
X344066Y614080D03*
X346581Y614095D03*
X351831Y610812D03*
X349316Y610797D03*
X378816D03*
X370802Y610812D03*
X368287Y610797D03*
X376081Y614095D03*
X373566Y614080D03*
X368301Y614065D03*
X370816Y614080D03*
X381331Y610812D03*
G54D39*
X380195Y257618D03*
X370195D03*
G54D17*
X24016Y58661D03*
X129134Y247543D03*
G54D29*
X87756Y89370D03*
X109095Y47244D03*
G54D32*
X347033Y247709D03*
%LPC*%
G75*
G54D40*
G01X-117168Y-317735D02*
Y-322735D01*
G01X-118625Y-317735D02*
X-115711D01*
G01X-110801Y-322735D02*
X-113335D01*
Y-317735D01*
X-110801D01*
G01X-111815Y-320152D02*
X-113335D01*
G01X-108235Y-317735D02*
Y-322735D01*
X-105701D01*
G01X-101868Y-322902D02*
X-101995Y-322818D01*
Y-322652D01*
X-101868Y-322568D01*
X-101741Y-322652D01*
Y-322818D01*
X-101868Y-322902D01*
G01Y-320652D02*
X-101995Y-320568D01*
Y-320402D01*
X-101868Y-320318D01*
X-101741Y-320402D01*
Y-320568D01*
X-101868Y-320652D01*
G01X-97085Y-324402D02*
X-97718Y-323568D01*
X-98035Y-322735D01*
Y-319402D01*
X-97718Y-318568D01*
X-97085Y-317735D01*
G01X-91668D02*
X-92175Y-317902D01*
X-92555Y-318318D01*
X-92808Y-318818D01*
X-92998Y-319485D01*
X-93061Y-320235D01*
X-92998Y-320985D01*
X-92808Y-321652D01*
X-92555Y-322152D01*
X-92175Y-322568D01*
X-91668Y-322735D01*
X-91161Y-322568D01*
X-90781Y-322152D01*
X-90528Y-321652D01*
X-90338Y-320985D01*
X-90275Y-320235D01*
X-90338Y-319485D01*
X-90528Y-318818D01*
X-90781Y-318318D01*
X-91161Y-317902D01*
X-91668Y-317735D01*
G01X-87961Y-321735D02*
X-87581Y-322318D01*
X-87075Y-322652D01*
X-86505Y-322735D01*
X-85998Y-322652D01*
X-85491Y-322235D01*
X-85175Y-321735D01*
X-85111Y-321235D01*
X-85238Y-320652D01*
X-85681Y-320235D01*
X-86125Y-320068D01*
X-86695D01*
G01X-86125D02*
X-85745Y-319818D01*
X-85428Y-319402D01*
X-85301Y-318902D01*
X-85428Y-318402D01*
X-85745Y-317985D01*
X-86315Y-317735D01*
X-86885Y-317818D01*
X-87455Y-318152D01*
G01X-81151Y-324402D02*
X-80518Y-323568D01*
X-80201Y-322735D01*
Y-319402D01*
X-80518Y-318568D01*
X-81151Y-317735D01*
G01X-77761Y-321735D02*
X-77381Y-322318D01*
X-76875Y-322652D01*
X-76305Y-322735D01*
X-75798Y-322652D01*
X-75291Y-322235D01*
X-74975Y-321735D01*
X-74911Y-321235D01*
X-75038Y-320652D01*
X-75481Y-320235D01*
X-75925Y-320068D01*
X-76495D01*
G01X-75925D02*
X-75545Y-319818D01*
X-75228Y-319402D01*
X-75101Y-318902D01*
X-75228Y-318402D01*
X-75545Y-317985D01*
X-76115Y-317735D01*
X-76685Y-317818D01*
X-77255Y-318152D01*
G01X-72471Y-318568D02*
X-72091Y-318068D01*
X-71648Y-317818D01*
X-71141Y-317735D01*
X-70508Y-317902D01*
X-70065Y-318318D01*
X-69938Y-318818D01*
X-70001Y-319318D01*
X-70255Y-319735D01*
X-71521Y-320568D01*
X-72091Y-321152D01*
X-72471Y-321985D01*
X-72598Y-322735D01*
X-69938D01*
G01X-66295D02*
X-66168Y-321652D01*
X-65978Y-320735D01*
X-65725Y-319902D01*
X-65408Y-318985D01*
X-64901Y-317735D01*
X-67435D01*
G01X-61891Y-321068D02*
X-60245D01*
G01X-57171Y-318568D02*
X-56791Y-318068D01*
X-56348Y-317818D01*
X-55841Y-317735D01*
X-55208Y-317902D01*
X-54765Y-318318D01*
X-54638Y-318818D01*
X-54701Y-319318D01*
X-54955Y-319735D01*
X-56221Y-320568D01*
X-56791Y-321152D01*
X-57171Y-321985D01*
X-57298Y-322735D01*
X-54638D01*
G01X-52261Y-321735D02*
X-51881Y-322318D01*
X-51375Y-322652D01*
X-50805Y-322735D01*
X-50298Y-322652D01*
X-49791Y-322235D01*
X-49475Y-321735D01*
X-49411Y-321235D01*
X-49538Y-320652D01*
X-49981Y-320235D01*
X-50425Y-320068D01*
X-50995D01*
G01X-50425D02*
X-50045Y-319818D01*
X-49728Y-319402D01*
X-49601Y-318902D01*
X-49728Y-318402D01*
X-50045Y-317985D01*
X-50615Y-317735D01*
X-51185Y-317818D01*
X-51755Y-318152D01*
G01X-45008Y-322735D02*
Y-317735D01*
X-47351Y-321318D01*
X-44185D01*
G01X-42061Y-321985D02*
X-41681Y-322402D01*
X-41238Y-322652D01*
X-40668Y-322735D01*
X-40098Y-322568D01*
X-39655Y-322235D01*
X-39338Y-321652D01*
X-39275Y-320985D01*
X-39401Y-320318D01*
X-39718Y-319902D01*
X-40161Y-319568D01*
X-40605Y-319485D01*
X-41048Y-319568D01*
X-41618Y-319902D01*
X-41428Y-317735D01*
X-39718D01*
G01X-31671Y-322735D02*
Y-317735D01*
X-29265D01*
G01X-30151Y-320152D02*
X-31671D01*
G01X-26951Y-322735D02*
X-25368Y-317735D01*
X-23785Y-322735D01*
G01X-24355Y-320985D02*
X-26381D01*
G01X-21598Y-322735D02*
X-18938Y-317735D01*
G01X-21598D02*
X-18938Y-322735D01*
G01X-15168Y-322902D02*
X-15295Y-322818D01*
Y-322652D01*
X-15168Y-322568D01*
X-15041Y-322652D01*
Y-322818D01*
X-15168Y-322902D01*
G01Y-320652D02*
X-15295Y-320568D01*
Y-320402D01*
X-15168Y-320318D01*
X-15041Y-320402D01*
Y-320568D01*
X-15168Y-320652D01*
G01X-10385Y-324402D02*
X-11018Y-323568D01*
X-11335Y-322735D01*
Y-319402D01*
X-11018Y-318568D01*
X-10385Y-317735D01*
G01X-4968D02*
X-5475Y-317902D01*
X-5855Y-318318D01*
X-6108Y-318818D01*
X-6298Y-319485D01*
X-6361Y-320235D01*
X-6298Y-320985D01*
X-6108Y-321652D01*
X-5855Y-322152D01*
X-5475Y-322568D01*
X-4968Y-322735D01*
X-4461Y-322568D01*
X-4081Y-322152D01*
X-3828Y-321652D01*
X-3638Y-320985D01*
X-3575Y-320235D01*
X-3638Y-319485D01*
X-3828Y-318818D01*
X-4081Y-318318D01*
X-4461Y-317902D01*
X-4968Y-317735D01*
G01X-1261Y-321735D02*
X-881Y-322318D01*
X-375Y-322652D01*
X195Y-322735D01*
X702Y-322652D01*
X1209Y-322235D01*
X1525Y-321735D01*
X1589Y-321235D01*
X1462Y-320652D01*
X1019Y-320235D01*
X575Y-320068D01*
X5D01*
G01X575D02*
X955Y-319818D01*
X1272Y-319402D01*
X1399Y-318902D01*
X1272Y-318402D01*
X955Y-317985D01*
X385Y-317735D01*
X-185Y-317818D01*
X-755Y-318152D01*
G01X5549Y-324402D02*
X6182Y-323568D01*
X6499Y-322735D01*
Y-319402D01*
X6182Y-318568D01*
X5549Y-317735D01*
G01X8939Y-321735D02*
X9319Y-322318D01*
X9825Y-322652D01*
X10395Y-322735D01*
X10902Y-322652D01*
X11409Y-322235D01*
X11725Y-321735D01*
X11789Y-321235D01*
X11662Y-320652D01*
X11219Y-320235D01*
X10775Y-320068D01*
X10205D01*
G01X10775D02*
X11155Y-319818D01*
X11472Y-319402D01*
X11599Y-318902D01*
X11472Y-318402D01*
X11155Y-317985D01*
X10585Y-317735D01*
X10015Y-317818D01*
X9445Y-318152D01*
G01X14355Y-322152D02*
X14799Y-322568D01*
X15305Y-322735D01*
X15812Y-322568D01*
X16255Y-322068D01*
X16572Y-321318D01*
X16699Y-320568D01*
Y-319652D01*
X16572Y-318902D01*
X16255Y-318235D01*
X15875Y-317902D01*
X15432Y-317735D01*
X14925Y-317902D01*
X14545Y-318235D01*
X14292Y-318735D01*
X14165Y-319402D01*
X14292Y-319985D01*
X14609Y-320568D01*
X14989Y-320902D01*
X15432Y-320985D01*
X15939Y-320818D01*
X16319Y-320402D01*
X16699Y-319652D01*
G01X20405Y-322735D02*
X20532Y-321652D01*
X20722Y-320735D01*
X20975Y-319902D01*
X21292Y-318985D01*
X21799Y-317735D01*
X19265D01*
G01X24809Y-321068D02*
X26455D01*
G01X29339Y-321735D02*
X29719Y-322318D01*
X30225Y-322652D01*
X30795Y-322735D01*
X31302Y-322652D01*
X31809Y-322235D01*
X32125Y-321735D01*
X32189Y-321235D01*
X32062Y-320652D01*
X31619Y-320235D01*
X31175Y-320068D01*
X30605D01*
G01X31175D02*
X31555Y-319818D01*
X31872Y-319402D01*
X31999Y-318902D01*
X31872Y-318402D01*
X31555Y-317985D01*
X30985Y-317735D01*
X30415Y-317818D01*
X29845Y-318152D01*
G01X34629Y-320652D02*
X35072Y-320068D01*
X35452Y-319735D01*
X35959Y-319568D01*
X36402Y-319735D01*
X36719Y-320068D01*
X36972Y-320568D01*
X37035Y-321152D01*
X36972Y-321652D01*
X36719Y-322152D01*
X36339Y-322568D01*
X35895Y-322735D01*
X35389Y-322568D01*
X34945Y-322068D01*
X34692Y-321318D01*
X34629Y-320485D01*
X34755Y-319402D01*
X34945Y-318818D01*
X35262Y-318235D01*
X35705Y-317818D01*
X36149Y-317735D01*
X36592Y-317902D01*
X36909Y-318318D01*
G01X40932Y-322735D02*
Y-317735D01*
X40172Y-318735D01*
G01Y-322735D02*
X41692D01*
G01X46792D02*
Y-317735D01*
X44449Y-321318D01*
X47615D01*
G01X-129168Y-252735D02*
Y-327735D01*
X370832D01*
Y-252735D01*
X-129168D01*
G01X65832D02*
Y-327735D01*
G01Y-302735D02*
X168832D01*
Y-277735D01*
G01X65832D02*
X168832D01*
G01X176339Y-312735D02*
Y-307735D01*
X177605D01*
X178112Y-307985D01*
X178492Y-308318D01*
X178809Y-308818D01*
X179062Y-309402D01*
X179125Y-310235D01*
X179062Y-311068D01*
X178809Y-311652D01*
X178492Y-312152D01*
X178112Y-312485D01*
X177605Y-312735D01*
X176339D01*
G01X181249D02*
X182832Y-307735D01*
X184415Y-312735D01*
G01X183845Y-310985D02*
X181819D01*
G01X187932Y-307735D02*
Y-312735D01*
G01X186475Y-307735D02*
X189389D01*
G01X194299Y-312735D02*
X191765D01*
Y-307735D01*
X194299D01*
G01X193285Y-310152D02*
X191765D01*
G01X198132Y-312902D02*
X198005Y-312818D01*
Y-312652D01*
X198132Y-312568D01*
X198259Y-312652D01*
Y-312818D01*
X198132Y-312902D01*
G01Y-310652D02*
X198005Y-310568D01*
Y-310402D01*
X198132Y-310318D01*
X198259Y-310402D01*
Y-310568D01*
X198132Y-310652D01*
G01X170832Y-252735D02*
Y-327735D01*
G01X168832Y-252735D02*
Y-327735D01*
G01X170832Y-302735D02*
X370832D01*
G01X176465Y-287735D02*
Y-282735D01*
X177985D01*
X178492Y-282985D01*
X178872Y-283568D01*
X178999Y-284235D01*
X178872Y-284902D01*
X178555Y-285402D01*
X177985Y-285652D01*
X176465D01*
G01X181692Y-287902D02*
X183972Y-282735D01*
G01X186475Y-287735D02*
Y-282735D01*
X189389Y-287735D01*
Y-282735D01*
G01X193032Y-287902D02*
X192905Y-287818D01*
Y-287652D01*
X193032Y-287568D01*
X193159Y-287652D01*
Y-287818D01*
X193032Y-287902D01*
G01Y-285652D02*
X192905Y-285568D01*
Y-285402D01*
X193032Y-285318D01*
X193159Y-285402D01*
Y-285568D01*
X193032Y-285652D01*
G01X170832Y-277735D02*
X370832D01*
G01X176465Y-262735D02*
Y-257735D01*
X177985D01*
X178492Y-257985D01*
X178872Y-258568D01*
X178999Y-259235D01*
X178872Y-259902D01*
X178555Y-260402D01*
X177985Y-260652D01*
X176465D01*
G01X181565Y-262735D02*
Y-257735D01*
X183149D01*
X183655Y-257985D01*
X183972Y-258318D01*
X184099Y-258985D01*
X183972Y-259652D01*
X183592Y-260068D01*
X183149Y-260318D01*
X181565D01*
G01X183149D02*
X184099Y-262735D01*
G01X187932D02*
X187425Y-262652D01*
X186982Y-262318D01*
X186602Y-261818D01*
X186349Y-261235D01*
X186222Y-260568D01*
Y-259902D01*
X186349Y-259235D01*
X186602Y-258652D01*
X186982Y-258152D01*
X187425Y-257818D01*
X187932Y-257735D01*
X188439Y-257818D01*
X188882Y-258152D01*
X189262Y-258652D01*
X189515Y-259235D01*
X189642Y-259902D01*
Y-260568D01*
X189515Y-261235D01*
X189262Y-261818D01*
X188882Y-262318D01*
X188439Y-262652D01*
X187932Y-262735D01*
G01X191765Y-261735D02*
X192082Y-262235D01*
X192462Y-262568D01*
X192905Y-262735D01*
X193412Y-262568D01*
X193792Y-262235D01*
X194172Y-261735D01*
X194299Y-261068D01*
Y-257735D01*
G01X199399Y-262735D02*
X196865D01*
Y-257735D01*
X199399D01*
G01X198385Y-260152D02*
X196865D01*
G01X204625Y-258152D02*
X204245Y-257902D01*
X203802Y-257735D01*
X203295D01*
X202725Y-257985D01*
X202282Y-258402D01*
X201965Y-258902D01*
X201712Y-259735D01*
X201649Y-260485D01*
X201775Y-261235D01*
X201965Y-261735D01*
X202345Y-262235D01*
X202789Y-262568D01*
X203232Y-262735D01*
X203675D01*
X204119Y-262568D01*
X204499Y-262318D01*
X204815Y-261985D01*
G01X208332Y-257735D02*
Y-262735D01*
G01X206875Y-257735D02*
X209789D01*
G01X213432Y-262902D02*
X213305Y-262818D01*
Y-262652D01*
X213432Y-262568D01*
X213559Y-262652D01*
Y-262818D01*
X213432Y-262902D01*
G01Y-260652D02*
X213305Y-260568D01*
Y-260402D01*
X213432Y-260318D01*
X213559Y-260402D01*
Y-260568D01*
X213432Y-260652D01*
G01X283832Y-302735D02*
Y-327735D01*
G01X288465Y-305235D02*
Y-310235D01*
X290999D01*
G01X294072Y-305235D02*
X295592D01*
G01X294832D02*
Y-310235D01*
G01X294072D02*
X295592D01*
G01X300439Y-307568D02*
X300692Y-307318D01*
X300882Y-306902D01*
X301009Y-306318D01*
X300882Y-305818D01*
X300629Y-305485D01*
X300185Y-305235D01*
X298475D01*
Y-310235D01*
X300565D01*
X301009Y-309902D01*
X301262Y-309402D01*
X301389Y-308818D01*
X301262Y-308235D01*
X300882Y-307735D01*
X300439Y-307568D01*
X298475D01*
G01X305032Y-310402D02*
X304905Y-310318D01*
Y-310152D01*
X305032Y-310068D01*
X305159Y-310152D01*
Y-310318D01*
X305032Y-310402D01*
G01Y-308152D02*
X304905Y-308068D01*
Y-307902D01*
X305032Y-307818D01*
X305159Y-307902D01*
Y-308068D01*
X305032Y-308152D01*
G01X328832Y-302735D02*
Y-327735D01*
G01X332732Y-305235D02*
Y-310235D01*
G01X331275Y-305235D02*
X334189D01*
G01X337832Y-310235D02*
X337452Y-310152D01*
X337072Y-309818D01*
X336819Y-309235D01*
X336692Y-308568D01*
X336819Y-307902D01*
X337072Y-307318D01*
X337452Y-306985D01*
X337832Y-306902D01*
X338212Y-306985D01*
X338592Y-307318D01*
X338845Y-307902D01*
X338909Y-308568D01*
X338845Y-309235D01*
X338592Y-309818D01*
X338212Y-310152D01*
X337832Y-310235D01*
G01X342932D02*
X342552Y-310152D01*
X342172Y-309818D01*
X341919Y-309235D01*
X341792Y-308568D01*
X341919Y-307902D01*
X342172Y-307318D01*
X342552Y-306985D01*
X342932Y-306902D01*
X343312Y-306985D01*
X343692Y-307318D01*
X343945Y-307902D01*
X344009Y-308568D01*
X343945Y-309235D01*
X343692Y-309818D01*
X343312Y-310152D01*
X342932Y-310235D01*
G01X348032D02*
Y-305235D01*
G01X353132Y-310402D02*
X353005Y-310318D01*
Y-310152D01*
X353132Y-310068D01*
X353259Y-310152D01*
Y-310318D01*
X353132Y-310402D01*
G01Y-308152D02*
X353005Y-308068D01*
Y-307902D01*
X353132Y-307818D01*
X353259Y-307902D01*
Y-308068D01*
X353132Y-308152D01*
G01X328832Y-277735D02*
Y-302735D01*
G01X331465Y-285235D02*
Y-280235D01*
X333049D01*
X333555Y-280485D01*
X333872Y-280818D01*
X333999Y-281485D01*
X333872Y-282152D01*
X333492Y-282568D01*
X333049Y-282818D01*
X331465D01*
G01X333049D02*
X333999Y-285235D01*
G01X339099D02*
X336565D01*
Y-280235D01*
X339099D01*
G01X338085Y-282652D02*
X336565D01*
G01X341349Y-280235D02*
X342932Y-285235D01*
X344515Y-280235D01*
G01X348032Y-285402D02*
X347905Y-285318D01*
Y-285152D01*
X348032Y-285068D01*
X348159Y-285152D01*
Y-285318D01*
X348032Y-285402D01*
G01Y-283152D02*
X347905Y-283068D01*
Y-282902D01*
X348032Y-282818D01*
X348159Y-282902D01*
Y-283068D01*
X348032Y-283152D01*
G01X351592Y-329435D02*
X351672Y-329360D01*
X351732Y-329235D01*
X351772Y-329060D01*
X351732Y-328910D01*
X351652Y-328810D01*
X351512Y-328735D01*
X350972D01*
Y-330235D01*
X351632D01*
X351772Y-330135D01*
X351852Y-329985D01*
X351892Y-329810D01*
X351852Y-329635D01*
X351732Y-329485D01*
X351592Y-329435D01*
X350972D01*
G01X352992Y-330235D02*
Y-329235D01*
G01Y-329410D02*
X352912Y-329310D01*
X352792Y-329260D01*
X352652Y-329235D01*
X352512Y-329285D01*
X352392Y-329385D01*
X352312Y-329535D01*
X352272Y-329735D01*
X352312Y-329935D01*
X352392Y-330085D01*
X352512Y-330185D01*
X352652Y-330235D01*
X352792Y-330210D01*
X352912Y-330135D01*
X352992Y-330035D01*
G01X353532Y-330060D02*
X353632Y-330160D01*
X353772Y-330235D01*
X353892D01*
X354012Y-330185D01*
X354092Y-330110D01*
X354132Y-330010D01*
X354112Y-329860D01*
X354032Y-329785D01*
X353672Y-329635D01*
X353592Y-329460D01*
X353632Y-329335D01*
X353712Y-329260D01*
X353832Y-329235D01*
X353952Y-329260D01*
X354072Y-329335D01*
G01X354732Y-329560D02*
X355372D01*
X355312Y-329385D01*
X355212Y-329285D01*
X355072Y-329235D01*
X354932Y-329260D01*
X354812Y-329335D01*
X354732Y-329510D01*
X354692Y-329660D01*
Y-329810D01*
X354732Y-329960D01*
X354832Y-330110D01*
X354952Y-330210D01*
X355092Y-330235D01*
X355232Y-330185D01*
X355372Y-330035D01*
G01X355872Y-330235D02*
Y-328735D01*
G01Y-329485D02*
X355972Y-329335D01*
X356092Y-329260D01*
X356212Y-329235D01*
X356392Y-329285D01*
X356512Y-329385D01*
X356592Y-329560D01*
Y-329760D01*
X356552Y-329960D01*
X356472Y-330110D01*
X356332Y-330210D01*
X356212Y-330235D01*
X356092Y-330210D01*
X355972Y-330135D01*
X355872Y-330010D01*
G01X357432Y-330235D02*
X357312Y-330210D01*
X357192Y-330110D01*
X357112Y-329935D01*
X357072Y-329735D01*
X357112Y-329535D01*
X357192Y-329360D01*
X357312Y-329260D01*
X357432Y-329235D01*
X357552Y-329260D01*
X357672Y-329360D01*
X357752Y-329535D01*
X357772Y-329735D01*
X357752Y-329935D01*
X357672Y-330110D01*
X357552Y-330210D01*
X357432Y-330235D01*
G01X358992D02*
Y-329235D01*
G01Y-329410D02*
X358912Y-329310D01*
X358792Y-329260D01*
X358652Y-329235D01*
X358512Y-329285D01*
X358392Y-329385D01*
X358312Y-329535D01*
X358272Y-329735D01*
X358312Y-329935D01*
X358392Y-330085D01*
X358512Y-330185D01*
X358652Y-330235D01*
X358792Y-330210D01*
X358912Y-330135D01*
X358992Y-330035D01*
G01X359552Y-330235D02*
Y-329235D01*
G01Y-329435D02*
X359652Y-329335D01*
X359752Y-329260D01*
X359892Y-329235D01*
X359992Y-329260D01*
X360112Y-329335D01*
G01X361392Y-328735D02*
Y-330235D01*
G01Y-330010D02*
X361312Y-330135D01*
X361192Y-330210D01*
X361052Y-330235D01*
X360892Y-330185D01*
X360772Y-330060D01*
X360692Y-329910D01*
X360672Y-329735D01*
X360692Y-329560D01*
X360772Y-329410D01*
X360892Y-329285D01*
X361052Y-329235D01*
X361192Y-329260D01*
X361292Y-329310D01*
X361392Y-329410D01*
G01X363032Y-330235D02*
Y-328735D01*
X363532D01*
X363692Y-328810D01*
X363792Y-328910D01*
X363832Y-329110D01*
X363792Y-329310D01*
X363672Y-329435D01*
X363532Y-329510D01*
X363032D01*
G01X363532D02*
X363832Y-330235D01*
G01X364332Y-329560D02*
X364972D01*
X364912Y-329385D01*
X364812Y-329285D01*
X364672Y-329235D01*
X364532Y-329260D01*
X364412Y-329335D01*
X364332Y-329510D01*
X364292Y-329660D01*
Y-329810D01*
X364332Y-329960D01*
X364432Y-330110D01*
X364552Y-330210D01*
X364692Y-330235D01*
X364832Y-330185D01*
X364972Y-330035D01*
G01X365472Y-329235D02*
X365832Y-330235D01*
X366192Y-329235D01*
G01X367032Y-330285D02*
X366992Y-330260D01*
Y-330210D01*
X367032Y-330185D01*
X367072Y-330210D01*
Y-330260D01*
X367032Y-330285D01*
G01X368192Y-330235D02*
X368232Y-329910D01*
X368292Y-329635D01*
X368372Y-329385D01*
X368472Y-329110D01*
X368632Y-328735D01*
X367832D01*
G01X369592Y-329435D02*
X369672Y-329360D01*
X369732Y-329235D01*
X369772Y-329060D01*
X369732Y-328910D01*
X369652Y-328810D01*
X369512Y-328735D01*
X368972D01*
Y-330235D01*
X369632D01*
X369772Y-330135D01*
X369852Y-329985D01*
X369892Y-329810D01*
X369852Y-329635D01*
X369732Y-329485D01*
X369592Y-329435D01*
X368972D01*
G01X-247901Y-428634D02*
Y1008173D01*
X2091018D01*
Y-428634D01*
X-247901D01*
G01X-115095Y-307460D02*
X-115565Y-307145D01*
X-116113Y-306935D01*
X-116740D01*
X-117445Y-307250D01*
X-117993Y-307775D01*
X-118385Y-308405D01*
X-118698Y-309455D01*
X-118776Y-310400D01*
X-118620Y-311345D01*
X-118385Y-311975D01*
X-117915Y-312605D01*
X-117366Y-313025D01*
X-116818Y-313235D01*
X-116270D01*
X-115721Y-313025D01*
X-115251Y-312710D01*
X-114860Y-312290D01*
G01X-111458Y-306935D02*
X-109578D01*
G01X-110518D02*
Y-313235D01*
G01X-111458D02*
X-109578D01*
G01X-104218Y-306935D02*
Y-313235D01*
G01X-106020Y-306935D02*
X-102416D01*
G01X-97918Y-313235D02*
Y-310400D01*
X-99485Y-306935D01*
G01X-96351D02*
X-97918Y-310400D01*
G01X-87041Y-311975D02*
X-86571Y-312710D01*
X-85945Y-313130D01*
X-85240Y-313235D01*
X-84613Y-313130D01*
X-83986Y-312605D01*
X-83595Y-311975D01*
X-83516Y-311345D01*
X-83673Y-310610D01*
X-84221Y-310085D01*
X-84770Y-309875D01*
X-85475D01*
G01X-84770D02*
X-84300Y-309560D01*
X-83908Y-309035D01*
X-83751Y-308405D01*
X-83908Y-307775D01*
X-84300Y-307250D01*
X-85005Y-306935D01*
X-85710Y-307040D01*
X-86415Y-307460D01*
G01X-80741Y-311975D02*
X-80271Y-312710D01*
X-79645Y-313130D01*
X-78940Y-313235D01*
X-78313Y-313130D01*
X-77686Y-312605D01*
X-77295Y-311975D01*
X-77216Y-311345D01*
X-77373Y-310610D01*
X-77921Y-310085D01*
X-78470Y-309875D01*
X-79175D01*
G01X-78470D02*
X-78000Y-309560D01*
X-77608Y-309035D01*
X-77451Y-308405D01*
X-77608Y-307775D01*
X-78000Y-307250D01*
X-78705Y-306935D01*
X-79410Y-307040D01*
X-80115Y-307460D01*
G01X-74441Y-311975D02*
X-73971Y-312710D01*
X-73345Y-313130D01*
X-72640Y-313235D01*
X-72013Y-313130D01*
X-71386Y-312605D01*
X-70995Y-311975D01*
X-70916Y-311345D01*
X-71073Y-310610D01*
X-71621Y-310085D01*
X-72170Y-309875D01*
X-72875D01*
G01X-72170D02*
X-71700Y-309560D01*
X-71308Y-309035D01*
X-71151Y-308405D01*
X-71308Y-307775D01*
X-71700Y-307250D01*
X-72405Y-306935D01*
X-73110Y-307040D01*
X-73815Y-307460D01*
G01X-66575Y-313235D02*
X-66418Y-311870D01*
X-66183Y-310715D01*
X-65870Y-309665D01*
X-65478Y-308510D01*
X-64851Y-306935D01*
X-67985D01*
G01X-60275Y-313235D02*
X-60118Y-311870D01*
X-59883Y-310715D01*
X-59570Y-309665D01*
X-59178Y-308510D01*
X-58551Y-306935D01*
X-61685D01*
G01X-53975Y-314390D02*
X-53661Y-313025D01*
G01X-47518Y-306935D02*
Y-313235D01*
G01X-49320Y-306935D02*
X-45716D01*
G01X-43176Y-313235D02*
X-41218Y-306935D01*
X-39260Y-313235D01*
G01X-39965Y-311030D02*
X-42471D01*
G01X-35858Y-306935D02*
X-33978D01*
G01X-34918D02*
Y-313235D01*
G01X-35858D02*
X-33978D01*
G01X-30968Y-306935D02*
X-29871Y-313235D01*
X-28618Y-306935D01*
X-27365Y-313235D01*
X-26268Y-306935D01*
G01X-24276Y-313235D02*
X-22318Y-306935D01*
X-20360Y-313235D01*
G01X-21065Y-311030D02*
X-23571D01*
G01X-17820Y-313235D02*
Y-306935D01*
X-14216Y-313235D01*
Y-306935D01*
G01X-3810Y-315335D02*
X-4593Y-314285D01*
X-4985Y-313235D01*
Y-309035D01*
X-4593Y-307985D01*
X-3810Y-306935D01*
G01X7615Y-313235D02*
Y-306935D01*
X9574D01*
X10200Y-307250D01*
X10592Y-307670D01*
X10749Y-308510D01*
X10592Y-309350D01*
X10122Y-309875D01*
X9574Y-310190D01*
X7615D01*
G01X9574D02*
X10749Y-313235D01*
G01X15482Y-313445D02*
X15325Y-313340D01*
Y-313130D01*
X15482Y-313025D01*
X15639Y-313130D01*
Y-313340D01*
X15482Y-313445D01*
G01X21782Y-313235D02*
X21155Y-313130D01*
X20607Y-312710D01*
X20137Y-312080D01*
X19824Y-311345D01*
X19667Y-310505D01*
Y-309665D01*
X19824Y-308825D01*
X20137Y-308090D01*
X20607Y-307460D01*
X21155Y-307040D01*
X21782Y-306935D01*
X22409Y-307040D01*
X22957Y-307460D01*
X23427Y-308090D01*
X23740Y-308825D01*
X23897Y-309665D01*
Y-310505D01*
X23740Y-311345D01*
X23427Y-312080D01*
X22957Y-312710D01*
X22409Y-313130D01*
X21782Y-313235D01*
G01X28082Y-313445D02*
X27925Y-313340D01*
Y-313130D01*
X28082Y-313025D01*
X28239Y-313130D01*
Y-313340D01*
X28082Y-313445D01*
G01X36105Y-307460D02*
X35635Y-307145D01*
X35087Y-306935D01*
X34460D01*
X33755Y-307250D01*
X33207Y-307775D01*
X32815Y-308405D01*
X32502Y-309455D01*
X32424Y-310400D01*
X32580Y-311345D01*
X32815Y-311975D01*
X33285Y-312605D01*
X33834Y-313025D01*
X34382Y-313235D01*
X34930D01*
X35479Y-313025D01*
X35949Y-312710D01*
X36340Y-312290D01*
G01X40682Y-313445D02*
X40525Y-313340D01*
Y-313130D01*
X40682Y-313025D01*
X40839Y-313130D01*
Y-313340D01*
X40682Y-313445D01*
G01X47374Y-315335D02*
X48157Y-314285D01*
X48549Y-313235D01*
Y-309035D01*
X48157Y-307985D01*
X47374Y-306935D01*
G01X-118620Y-293235D02*
Y-286935D01*
X-115016Y-293235D01*
Y-286935D01*
G01X-110518Y-293235D02*
X-111145Y-293130D01*
X-111693Y-292710D01*
X-112163Y-292080D01*
X-112476Y-291345D01*
X-112633Y-290505D01*
Y-289665D01*
X-112476Y-288825D01*
X-112163Y-288090D01*
X-111693Y-287460D01*
X-111145Y-287040D01*
X-110518Y-286935D01*
X-109891Y-287040D01*
X-109343Y-287460D01*
X-108873Y-288090D01*
X-108560Y-288825D01*
X-108403Y-289665D01*
Y-290505D01*
X-108560Y-291345D01*
X-108873Y-292080D01*
X-109343Y-292710D01*
X-109891Y-293130D01*
X-110518Y-293235D01*
G01X-104218Y-293445D02*
X-104375Y-293340D01*
Y-293130D01*
X-104218Y-293025D01*
X-104061Y-293130D01*
Y-293340D01*
X-104218Y-293445D01*
G01X-99406Y-287985D02*
X-98936Y-287355D01*
X-98388Y-287040D01*
X-97761Y-286935D01*
X-96978Y-287145D01*
X-96430Y-287670D01*
X-96273Y-288300D01*
X-96351Y-288930D01*
X-96665Y-289455D01*
X-98231Y-290505D01*
X-98936Y-291240D01*
X-99406Y-292290D01*
X-99563Y-293235D01*
X-96273D01*
G01X-91618D02*
Y-286935D01*
X-92558Y-288195D01*
G01Y-293235D02*
X-90678D01*
G01X-85318D02*
Y-286935D01*
X-86258Y-288195D01*
G01Y-293235D02*
X-84378D01*
G01X-79175Y-294390D02*
X-78861Y-293025D01*
G01X-75068Y-286935D02*
X-73971Y-293235D01*
X-72718Y-286935D01*
X-71465Y-293235D01*
X-70368Y-286935D01*
G01X-64851Y-293235D02*
X-67985D01*
Y-286935D01*
X-64851D01*
G01X-66105Y-289980D02*
X-67985D01*
G01X-61920Y-293235D02*
Y-286935D01*
X-58316Y-293235D01*
Y-286935D01*
G01X-55463Y-293235D02*
Y-286935D01*
G01X-52173D02*
Y-293235D01*
G01Y-290085D02*
X-55463D01*
G01X-49241Y-286935D02*
Y-291450D01*
X-48928Y-292395D01*
X-48301Y-293025D01*
X-47518Y-293235D01*
X-46735Y-293025D01*
X-46108Y-292395D01*
X-45795Y-291450D01*
Y-286935D01*
G01X-43176Y-293235D02*
X-41218Y-286935D01*
X-39260Y-293235D01*
G01X-39965Y-291030D02*
X-42471D01*
G01X-30106Y-287985D02*
X-29636Y-287355D01*
X-29088Y-287040D01*
X-28461Y-286935D01*
X-27678Y-287145D01*
X-27130Y-287670D01*
X-26973Y-288300D01*
X-27051Y-288930D01*
X-27365Y-289455D01*
X-28931Y-290505D01*
X-29636Y-291240D01*
X-30106Y-292290D01*
X-30263Y-293235D01*
X-26973D01*
G01X-24120D02*
Y-286935D01*
X-20516Y-293235D01*
Y-286935D01*
G01X-17741Y-293235D02*
Y-286935D01*
X-16175D01*
X-15548Y-287250D01*
X-15078Y-287670D01*
X-14686Y-288300D01*
X-14373Y-289035D01*
X-14295Y-290085D01*
X-14373Y-291135D01*
X-14686Y-291870D01*
X-15078Y-292500D01*
X-15548Y-292920D01*
X-16175Y-293235D01*
X-17741D01*
G01X-4985D02*
Y-286935D01*
X-3026D01*
X-2400Y-287250D01*
X-2008Y-287670D01*
X-1851Y-288510D01*
X-2008Y-289350D01*
X-2478Y-289875D01*
X-3026Y-290190D01*
X-4985D01*
G01X-3026D02*
X-1851Y-293235D01*
G01X1159D02*
Y-286935D01*
X2725D01*
X3352Y-287250D01*
X3822Y-287670D01*
X4214Y-288300D01*
X4527Y-289035D01*
X4605Y-290085D01*
X4527Y-291135D01*
X4214Y-291870D01*
X3822Y-292500D01*
X3352Y-292920D01*
X2725Y-293235D01*
X1159D01*
G01X9182Y-293445D02*
X9025Y-293340D01*
Y-293130D01*
X9182Y-293025D01*
X9339Y-293130D01*
Y-293340D01*
X9182Y-293445D01*
G01X-116348Y-300085D02*
X-114781D01*
Y-301975D01*
X-115251Y-302605D01*
X-115800Y-303025D01*
X-116583Y-303235D01*
X-117366Y-303025D01*
X-117915Y-302605D01*
X-118385Y-301975D01*
X-118698Y-301240D01*
X-118855Y-300400D01*
Y-299665D01*
X-118698Y-299035D01*
X-118385Y-298300D01*
X-117915Y-297670D01*
X-117445Y-297250D01*
X-116818Y-296935D01*
X-116270D01*
X-115643Y-297145D01*
X-115173Y-297565D01*
G01X-112241Y-296935D02*
Y-301450D01*
X-111928Y-302395D01*
X-111301Y-303025D01*
X-110518Y-303235D01*
X-109735Y-303025D01*
X-109108Y-302395D01*
X-108795Y-301450D01*
Y-296935D01*
G01X-105158D02*
X-103278D01*
G01X-104218D02*
Y-303235D01*
G01X-105158D02*
X-103278D01*
G01X-99563Y-302395D02*
X-98936Y-302920D01*
X-98231Y-303235D01*
X-97605D01*
X-96978Y-302920D01*
X-96508Y-302395D01*
X-96273Y-301660D01*
X-96430Y-300925D01*
X-96821Y-300295D01*
X-97526Y-299875D01*
X-98466Y-299665D01*
X-99015Y-299245D01*
X-99250Y-298510D01*
X-99093Y-297775D01*
X-98701Y-297250D01*
X-98153Y-296935D01*
X-97605D01*
X-97056Y-297145D01*
X-96586Y-297670D01*
G01X-93263Y-303235D02*
Y-296935D01*
G01X-89973D02*
Y-303235D01*
G01Y-300085D02*
X-93263D01*
G01X-87276Y-303235D02*
X-85318Y-296935D01*
X-83360Y-303235D01*
G01X-84065Y-301030D02*
X-86571D01*
G01X-80820Y-303235D02*
Y-296935D01*
X-77216Y-303235D01*
Y-296935D01*
G01X-68141Y-303235D02*
Y-296935D01*
X-66575D01*
X-65948Y-297250D01*
X-65478Y-297670D01*
X-65086Y-298300D01*
X-64773Y-299035D01*
X-64695Y-300085D01*
X-64773Y-301135D01*
X-65086Y-301870D01*
X-65478Y-302500D01*
X-65948Y-302920D01*
X-66575Y-303235D01*
X-68141D01*
G01X-61058Y-296935D02*
X-59178D01*
G01X-60118D02*
Y-303235D01*
G01X-61058D02*
X-59178D01*
G01X-55463Y-302395D02*
X-54836Y-302920D01*
X-54131Y-303235D01*
X-53505D01*
X-52878Y-302920D01*
X-52408Y-302395D01*
X-52173Y-301660D01*
X-52330Y-300925D01*
X-52721Y-300295D01*
X-53426Y-299875D01*
X-54366Y-299665D01*
X-54915Y-299245D01*
X-55150Y-298510D01*
X-54993Y-297775D01*
X-54601Y-297250D01*
X-54053Y-296935D01*
X-53505D01*
X-52956Y-297145D01*
X-52486Y-297670D01*
G01X-47518Y-296935D02*
Y-303235D01*
G01X-49320Y-296935D02*
X-45716D01*
G01X-41218Y-303445D02*
X-41375Y-303340D01*
Y-303130D01*
X-41218Y-303025D01*
X-41061Y-303130D01*
Y-303340D01*
X-41218Y-303445D01*
G01X-35075Y-304390D02*
X-34761Y-303025D01*
G01X-28618Y-296935D02*
Y-303235D01*
G01X-30420Y-296935D02*
X-26816D01*
G01X-24276Y-303235D02*
X-22318Y-296935D01*
X-20360Y-303235D01*
G01X-21065Y-301030D02*
X-23571D01*
G01X-16018Y-303235D02*
X-16645Y-303130D01*
X-17193Y-302710D01*
X-17663Y-302080D01*
X-17976Y-301345D01*
X-18133Y-300505D01*
Y-299665D01*
X-17976Y-298825D01*
X-17663Y-298090D01*
X-17193Y-297460D01*
X-16645Y-297040D01*
X-16018Y-296935D01*
X-15391Y-297040D01*
X-14843Y-297460D01*
X-14373Y-298090D01*
X-14060Y-298825D01*
X-13903Y-299665D01*
Y-300505D01*
X-14060Y-301345D01*
X-14373Y-302080D01*
X-14843Y-302710D01*
X-15391Y-303130D01*
X-16018Y-303235D01*
G01X-9718D02*
Y-300400D01*
X-11285Y-296935D01*
G01X-8151D02*
X-9718Y-300400D01*
G01X-5141Y-296935D02*
Y-301450D01*
X-4828Y-302395D01*
X-4201Y-303025D01*
X-3418Y-303235D01*
X-2635Y-303025D01*
X-2008Y-302395D01*
X-1695Y-301450D01*
Y-296935D01*
G01X924Y-303235D02*
X2882Y-296935D01*
X4840Y-303235D01*
G01X4135Y-301030D02*
X1629D01*
G01X7380Y-303235D02*
Y-296935D01*
X10984Y-303235D01*
Y-296935D01*
G01X-94518Y-282535D02*
X-97038Y-282118D01*
X-99243Y-280452D01*
X-101133Y-277952D01*
X-102393Y-275035D01*
X-103023Y-271702D01*
Y-268368D01*
X-102393Y-265035D01*
X-101133Y-262118D01*
X-99243Y-259619D01*
X-97038Y-257952D01*
X-94518Y-257535D01*
X-91998Y-257952D01*
X-89793Y-259619D01*
X-87903Y-262118D01*
X-86643Y-265035D01*
X-86013Y-268368D01*
Y-271702D01*
X-86643Y-275035D01*
X-87903Y-277952D01*
X-89793Y-280452D01*
X-91998Y-282118D01*
X-94518Y-282535D01*
G01X-91998Y-275868D02*
X-88218Y-282535D01*
G01X-74673Y-265869D02*
Y-277535D01*
X-73413Y-280452D01*
X-71523Y-282118D01*
X-69318Y-282535D01*
X-67113Y-282118D01*
X-65223Y-280452D01*
X-63963Y-277535D01*
G01Y-282535D02*
Y-265869D01*
G01X-38448Y-282535D02*
Y-265869D01*
G01Y-268785D02*
X-39708Y-267119D01*
X-41598Y-266285D01*
X-43803Y-265869D01*
X-46008Y-266702D01*
X-47898Y-268368D01*
X-49158Y-270869D01*
X-49788Y-274202D01*
X-49158Y-277535D01*
X-47898Y-280036D01*
X-46008Y-281702D01*
X-43803Y-282535D01*
X-41598Y-282118D01*
X-39708Y-280869D01*
X-38448Y-279202D01*
G01X-24273Y-282535D02*
Y-265869D01*
G01Y-270035D02*
X-23013Y-267952D01*
X-21123Y-266285D01*
X-18603Y-265869D01*
X-16398Y-266285D01*
X-14508Y-267952D01*
X-13563Y-270869D01*
Y-282535D01*
G01X6282Y-257535D02*
Y-282535D01*
G01X1872Y-265869D02*
X10692D01*
G01X37152Y-282535D02*
Y-265869D01*
G01Y-268785D02*
X35892Y-267119D01*
X34002Y-266285D01*
X31797Y-265869D01*
X29592Y-266702D01*
X27702Y-268368D01*
X26442Y-270869D01*
X25812Y-274202D01*
X26442Y-277535D01*
X27702Y-280036D01*
X29592Y-281702D01*
X31797Y-282535D01*
X34002Y-282118D01*
X35892Y-280869D01*
X37152Y-279202D01*
G01X76832Y-262235D02*
Y-270235D01*
X80832D01*
G01X88632D02*
Y-264902D01*
G01Y-265835D02*
X88232Y-265302D01*
X87632Y-265035D01*
X86932Y-264902D01*
X86232Y-265168D01*
X85632Y-265702D01*
X85232Y-266502D01*
X85032Y-267568D01*
X85232Y-268635D01*
X85632Y-269435D01*
X86232Y-269968D01*
X86932Y-270235D01*
X87632Y-270102D01*
X88232Y-269702D01*
X88632Y-269169D01*
G01X92732Y-272635D02*
X93332Y-272902D01*
X94132Y-272635D01*
X94632Y-272102D01*
X95032Y-271435D01*
X95632Y-269302D01*
X96932Y-264902D01*
G01X93732D02*
X95632Y-269302D01*
G01X101332Y-266635D02*
X104532D01*
X104232Y-265702D01*
X103732Y-265168D01*
X103032Y-264902D01*
X102332Y-265035D01*
X101732Y-265435D01*
X101332Y-266368D01*
X101132Y-267169D01*
Y-267968D01*
X101332Y-268768D01*
X101832Y-269568D01*
X102432Y-270102D01*
X103132Y-270235D01*
X103832Y-269968D01*
X104532Y-269169D01*
G01X109432Y-270235D02*
Y-264902D01*
G01Y-265968D02*
X109932Y-265435D01*
X110432Y-265035D01*
X111132Y-264902D01*
X111632Y-265035D01*
X112232Y-265435D01*
G01X95532Y-320235D02*
Y-312235D01*
X100132Y-320235D01*
Y-312235D01*
G01X105832Y-314902D02*
Y-320235D01*
G01Y-312768D02*
X105632Y-312635D01*
Y-312368D01*
X105832Y-312235D01*
X106032Y-312368D01*
Y-312635D01*
X105832Y-312768D01*
G01X112132Y-320235D02*
Y-314902D01*
G01Y-316235D02*
X112532Y-315568D01*
X113132Y-315035D01*
X113932Y-314902D01*
X114632Y-315035D01*
X115232Y-315568D01*
X115532Y-316502D01*
Y-320235D01*
G01X123632D02*
Y-314902D01*
G01Y-315835D02*
X123232Y-315302D01*
X122632Y-315035D01*
X121932Y-314902D01*
X121232Y-315168D01*
X120632Y-315702D01*
X120232Y-316502D01*
X120032Y-317568D01*
X120232Y-318635D01*
X120632Y-319435D01*
X121232Y-319968D01*
X121932Y-320235D01*
X122632Y-320102D01*
X123232Y-319702D01*
X123632Y-319169D01*
G01X108432Y-291235D02*
X110432D01*
Y-293635D01*
X109832Y-294435D01*
X109132Y-294968D01*
X108132Y-295235D01*
X107132Y-294968D01*
X106432Y-294435D01*
X105832Y-293635D01*
X105432Y-292702D01*
X105232Y-291635D01*
Y-290702D01*
X105432Y-289902D01*
X105832Y-288968D01*
X106432Y-288168D01*
X107032Y-287635D01*
X107832Y-287235D01*
X108532D01*
X109332Y-287502D01*
X109932Y-288035D01*
G01X113532Y-295235D02*
Y-287235D01*
X118132Y-295235D01*
Y-287235D01*
G01X121632Y-295235D02*
Y-287235D01*
X123632D01*
X124432Y-287635D01*
X125032Y-288168D01*
X125532Y-288968D01*
X125932Y-289902D01*
X126032Y-291235D01*
X125932Y-292568D01*
X125532Y-293502D01*
X125032Y-294302D01*
X124432Y-294835D01*
X123632Y-295235D01*
X121632D01*
G01X131832D02*
Y-287235D01*
X130632Y-288835D01*
G01Y-295235D02*
X133032D01*
G01X128132Y-268635D02*
X128732Y-269568D01*
X129532Y-270102D01*
X130432Y-270235D01*
X131232Y-270102D01*
X132032Y-269435D01*
X132532Y-268635D01*
X132632Y-267835D01*
X132432Y-266902D01*
X131732Y-266235D01*
X131032Y-265968D01*
X130132D01*
G01X131032D02*
X131632Y-265568D01*
X132132Y-264902D01*
X132332Y-264102D01*
X132132Y-263302D01*
X131632Y-262635D01*
X130732Y-262235D01*
X129832Y-262368D01*
X128932Y-262902D01*
G01X203432Y-313568D02*
X204032Y-312768D01*
X204732Y-312368D01*
X205532Y-312235D01*
X206532Y-312502D01*
X207232Y-313168D01*
X207432Y-313968D01*
X207332Y-314769D01*
X206932Y-315435D01*
X204932Y-316768D01*
X204032Y-317702D01*
X203432Y-319035D01*
X203232Y-320235D01*
X207432D01*
G01X213332Y-312235D02*
X212532Y-312502D01*
X211932Y-313168D01*
X211532Y-313968D01*
X211232Y-315035D01*
X211132Y-316235D01*
X211232Y-317435D01*
X211532Y-318502D01*
X211932Y-319302D01*
X212532Y-319968D01*
X213332Y-320235D01*
X214132Y-319968D01*
X214732Y-319302D01*
X215132Y-318502D01*
X215432Y-317435D01*
X215532Y-316235D01*
X215432Y-315035D01*
X215132Y-313968D01*
X214732Y-313168D01*
X214132Y-312502D01*
X213332Y-312235D01*
G01X219432Y-313568D02*
X220032Y-312768D01*
X220732Y-312368D01*
X221532Y-312235D01*
X222532Y-312502D01*
X223232Y-313168D01*
X223432Y-313968D01*
X223332Y-314769D01*
X222932Y-315435D01*
X220932Y-316768D01*
X220032Y-317702D01*
X219432Y-319035D01*
X219232Y-320235D01*
X223432D01*
G01X227432Y-313568D02*
X228032Y-312768D01*
X228732Y-312368D01*
X229532Y-312235D01*
X230532Y-312502D01*
X231232Y-313168D01*
X231432Y-313968D01*
X231332Y-314769D01*
X230932Y-315435D01*
X228932Y-316768D01*
X228032Y-317702D01*
X227432Y-319035D01*
X227232Y-320235D01*
X231432D01*
G01X235532Y-320502D02*
X239132Y-312235D01*
G01X245332Y-320235D02*
Y-312235D01*
X244132Y-313835D01*
G01Y-320235D02*
X246532D01*
G01X251432Y-313568D02*
X252032Y-312768D01*
X252732Y-312368D01*
X253532Y-312235D01*
X254532Y-312502D01*
X255232Y-313168D01*
X255432Y-313968D01*
X255332Y-314769D01*
X254932Y-315435D01*
X252932Y-316768D01*
X252032Y-317702D01*
X251432Y-319035D01*
X251232Y-320235D01*
X255432D01*
G01X259532Y-320502D02*
X263132Y-312235D01*
G01X269332D02*
X268532Y-312502D01*
X267932Y-313168D01*
X267532Y-313968D01*
X267232Y-315035D01*
X267132Y-316235D01*
X267232Y-317435D01*
X267532Y-318502D01*
X267932Y-319302D01*
X268532Y-319968D01*
X269332Y-320235D01*
X270132Y-319968D01*
X270732Y-319302D01*
X271132Y-318502D01*
X271432Y-317435D01*
X271532Y-316235D01*
X271432Y-315035D01*
X271132Y-313968D01*
X270732Y-313168D01*
X270132Y-312502D01*
X269332Y-312235D01*
G01X275632Y-319302D02*
X276332Y-319968D01*
X277132Y-320235D01*
X277932Y-319968D01*
X278632Y-319169D01*
X279132Y-317968D01*
X279332Y-316768D01*
Y-315302D01*
X279132Y-314102D01*
X278632Y-313035D01*
X278032Y-312502D01*
X277332Y-312235D01*
X276532Y-312502D01*
X275932Y-313035D01*
X275532Y-313835D01*
X275332Y-314902D01*
X275532Y-315835D01*
X276032Y-316768D01*
X276632Y-317302D01*
X277332Y-317435D01*
X278132Y-317169D01*
X278732Y-316502D01*
X279332Y-315302D01*
G01X205632Y-295235D02*
Y-287235D01*
X207632D01*
X208432Y-287635D01*
X209032Y-288168D01*
X209532Y-288968D01*
X209932Y-289902D01*
X210032Y-291235D01*
X209932Y-292568D01*
X209532Y-293502D01*
X209032Y-294302D01*
X208432Y-294835D01*
X207632Y-295235D01*
X205632D01*
G01X213332D02*
X215832Y-287235D01*
X218332Y-295235D01*
G01X217432Y-292435D02*
X214232D01*
G01X223832Y-287235D02*
X223032Y-287502D01*
X222432Y-288168D01*
X222032Y-288968D01*
X221732Y-290035D01*
X221632Y-291235D01*
X221732Y-292435D01*
X222032Y-293502D01*
X222432Y-294302D01*
X223032Y-294968D01*
X223832Y-295235D01*
X224632Y-294968D01*
X225232Y-294302D01*
X225632Y-293502D01*
X225932Y-292435D01*
X226032Y-291235D01*
X225932Y-290035D01*
X225632Y-288968D01*
X225232Y-288168D01*
X224632Y-287502D01*
X223832Y-287235D01*
G01X229932Y-295235D02*
Y-287235D01*
X233732D01*
G01X232332Y-291102D02*
X229932D01*
G01X239832Y-287235D02*
X239032Y-287502D01*
X238432Y-288168D01*
X238032Y-288968D01*
X237732Y-290035D01*
X237632Y-291235D01*
X237732Y-292435D01*
X238032Y-293502D01*
X238432Y-294302D01*
X239032Y-294968D01*
X239832Y-295235D01*
X240632Y-294968D01*
X241232Y-294302D01*
X241632Y-293502D01*
X241932Y-292435D01*
X242032Y-291235D01*
X241932Y-290035D01*
X241632Y-288968D01*
X241232Y-288168D01*
X240632Y-287502D01*
X239832Y-287235D01*
G01X247832D02*
Y-295235D01*
G01X245532Y-287235D02*
X250132D01*
G01X255832Y-295235D02*
Y-291635D01*
X253832Y-287235D01*
G01X257832D02*
X255832Y-291635D01*
G01X264632Y-290968D02*
X265032Y-290568D01*
X265332Y-289902D01*
X265532Y-288968D01*
X265332Y-288168D01*
X264932Y-287635D01*
X264232Y-287235D01*
X261532D01*
Y-295235D01*
X264832D01*
X265532Y-294702D01*
X265932Y-293902D01*
X266132Y-292968D01*
X265932Y-292035D01*
X265332Y-291235D01*
X264632Y-290968D01*
X261532D01*
G01X273032Y-295235D02*
Y-287235D01*
X269332Y-292968D01*
X274332D01*
G01X277632Y-295235D02*
Y-287235D01*
X279632D01*
X280432Y-287635D01*
X281032Y-288168D01*
X281532Y-288968D01*
X281932Y-289902D01*
X282032Y-291235D01*
X281932Y-292568D01*
X281532Y-293502D01*
X281032Y-294302D01*
X280432Y-294835D01*
X279632Y-295235D01*
X277632D01*
G01X287832Y-287235D02*
X287032Y-287502D01*
X286432Y-288168D01*
X286032Y-288968D01*
X285732Y-290035D01*
X285632Y-291235D01*
X285732Y-292435D01*
X286032Y-293502D01*
X286432Y-294302D01*
X287032Y-294968D01*
X287832Y-295235D01*
X288632Y-294968D01*
X289232Y-294302D01*
X289632Y-293502D01*
X289932Y-292435D01*
X290032Y-291235D01*
X289932Y-290035D01*
X289632Y-288968D01*
X289232Y-288168D01*
X288632Y-287502D01*
X287832Y-287235D01*
G01X233432Y-270235D02*
Y-262235D01*
X237232D01*
G01X235832Y-266102D02*
X233432D01*
G01X243332Y-262235D02*
X242532Y-262502D01*
X241932Y-263168D01*
X241532Y-263968D01*
X241232Y-265035D01*
X241132Y-266235D01*
X241232Y-267435D01*
X241532Y-268502D01*
X241932Y-269302D01*
X242532Y-269968D01*
X243332Y-270235D01*
X244132Y-269968D01*
X244732Y-269302D01*
X245132Y-268502D01*
X245432Y-267435D01*
X245532Y-266235D01*
X245432Y-265035D01*
X245132Y-263968D01*
X244732Y-263168D01*
X244132Y-262502D01*
X243332Y-262235D01*
G01X251332D02*
Y-270235D01*
G01X249032Y-262235D02*
X253632D01*
G01X256332Y-272902D02*
X262332D01*
G01X265332Y-270235D02*
Y-262235D01*
X267732D01*
X268532Y-262635D01*
X269132Y-263568D01*
X269332Y-264635D01*
X269132Y-265702D01*
X268632Y-266502D01*
X267732Y-266902D01*
X265332D01*
G01X272832Y-270235D02*
X275332Y-262235D01*
X277832Y-270235D01*
G01X276932Y-267435D02*
X273732D01*
G01X281032Y-270235D02*
Y-262235D01*
X285632Y-270235D01*
Y-262235D01*
G01X293332Y-270235D02*
X289332D01*
Y-262235D01*
X293332D01*
G01X291732Y-266102D02*
X289332D01*
G01X297332Y-262235D02*
Y-270235D01*
X301332D01*
G01X304332Y-272902D02*
X310332D01*
G01X316132Y-265968D02*
X316532Y-265568D01*
X316832Y-264902D01*
X317032Y-263968D01*
X316832Y-263168D01*
X316432Y-262635D01*
X315732Y-262235D01*
X313032D01*
Y-270235D01*
X316332D01*
X317032Y-269702D01*
X317432Y-268902D01*
X317632Y-267968D01*
X317432Y-267035D01*
X316832Y-266235D01*
X316132Y-265968D01*
X313032D01*
G01X321132Y-270235D02*
Y-262235D01*
X323132D01*
X323932Y-262635D01*
X324532Y-263168D01*
X325032Y-263968D01*
X325432Y-264902D01*
X325532Y-266235D01*
X325432Y-267568D01*
X325032Y-268502D01*
X324532Y-269302D01*
X323932Y-269835D01*
X323132Y-270235D01*
X321132D01*
G01X291832Y-323235D02*
Y-315235D01*
X290632Y-316835D01*
G01Y-323235D02*
X293032D01*
G01X297932Y-319902D02*
X298632Y-318968D01*
X299232Y-318435D01*
X300032Y-318168D01*
X300732Y-318435D01*
X301232Y-318968D01*
X301632Y-319768D01*
X301732Y-320702D01*
X301632Y-321502D01*
X301232Y-322302D01*
X300632Y-322968D01*
X299932Y-323235D01*
X299132Y-322968D01*
X298432Y-322169D01*
X298032Y-320968D01*
X297932Y-319635D01*
X298132Y-317902D01*
X298432Y-316968D01*
X298932Y-316035D01*
X299632Y-315368D01*
X300332Y-315235D01*
X301032Y-315502D01*
X301532Y-316168D01*
G01X307832Y-323502D02*
X307632Y-323368D01*
Y-323102D01*
X307832Y-322968D01*
X308032Y-323102D01*
Y-323368D01*
X307832Y-323502D01*
G01X313932Y-319902D02*
X314632Y-318968D01*
X315232Y-318435D01*
X316032Y-318168D01*
X316732Y-318435D01*
X317232Y-318968D01*
X317632Y-319768D01*
X317732Y-320702D01*
X317632Y-321502D01*
X317232Y-322302D01*
X316632Y-322968D01*
X315932Y-323235D01*
X315132Y-322968D01*
X314432Y-322169D01*
X314032Y-320968D01*
X313932Y-319635D01*
X314132Y-317902D01*
X314432Y-316968D01*
X314932Y-316035D01*
X315632Y-315368D01*
X316332Y-315235D01*
X317032Y-315502D01*
X317532Y-316168D01*
G01X336832Y-323235D02*
Y-315235D01*
X335632Y-316835D01*
G01Y-323235D02*
X338032D01*
G01X344632D02*
X344832Y-321502D01*
X345132Y-320035D01*
X345532Y-318702D01*
X346032Y-317235D01*
X346832Y-315235D01*
X342832D01*
G01X352832Y-323502D02*
X352632Y-323368D01*
Y-323102D01*
X352832Y-322968D01*
X353032Y-323102D01*
Y-323368D01*
X352832Y-323502D01*
G01X358932Y-316568D02*
X359532Y-315768D01*
X360232Y-315368D01*
X361032Y-315235D01*
X362032Y-315502D01*
X362732Y-316168D01*
X362932Y-316968D01*
X362832Y-317769D01*
X362432Y-318435D01*
X360432Y-319768D01*
X359532Y-320702D01*
X358932Y-322035D01*
X358732Y-323235D01*
X362932D01*
G01X356632Y-298235D02*
Y-290235D01*
X358632D01*
X359432Y-290635D01*
X360032Y-291168D01*
X360532Y-291968D01*
X360932Y-292902D01*
X361032Y-294235D01*
X360932Y-295568D01*
X360532Y-296502D01*
X360032Y-297302D01*
X359432Y-297835D01*
X358632Y-298235D01*
X356632D01*
M02*
